# S9S_MB_2U (Grand Teton) — schematic netlist excerpt (pin names and nets, part order shuffled) for the footprints in the layout excerpt that follows; sources: Cadence DE-HDL packaged netlist, KiCad conversion of 03242023_DA0F0TMBIJ0_F0T_Motherboard_J_brd_V01_OCP.brd

C857  Q_CAP_DIFFBUS  DIFF BUS_0.22UF 6.3V 20% X6S  pkg C0201  page 174 : \1\ = P5E_CPU0_PE1_TX_C_DP<6> ; \2\ = P5E_CPU0_PE1_TX_DP<6>
L16  Q_INDUCTOR  BLM18PG300SN1D IND  pkg SMLF  page 250 : \1\ = P3V3_AUX ; \2\ = P3V3_ADC128_VCC
C569  Q_CAP  0.1UF 25V 10% X7R  pkg 0402  page 236 : A = P3V3_AUX ; B = GND

(kicad_pcb
	(version 20260206)
	(generator "pcbnew")
	(generator_version "10.0")
	(general
		(thickness 1.6)
		(legacy_teardrops no)
	)
	(paper "A4")
	(title_block
		(title "03242023_DA0F0TMBIJ0_F0T_Motherboard_J_brd_V01_OCP.brd")
		(comment 1 "Grand Teton / footprints 3467-3469 of 6105")
	)
	(layers
		(0 "F.Cu" signal "TOP")
		(4 "In1.Cu" signal "GND")
		(6 "In2.Cu" signal "IN1")
		(8 "In3.Cu" signal "GND1")
		(10 "In4.Cu" signal "IN2")
		(12 "In5.Cu" signal "GND2")
		(14 "In6.Cu" signal "IN3")
		(16 "In7.Cu" signal "GND3")
		(18 "In8.Cu" signal "VCC")
		(20 "In9.Cu" signal "VCC1")
		(22 "In10.Cu" signal "GND4")
		(24 "In11.Cu" signal "IN4")
		(26 "In12.Cu" signal "GND5")
		(28 "In13.Cu" signal "IN5")
		(30 "In14.Cu" signal "GND6")
		(32 "In15.Cu" signal "IN6")
		(34 "In16.Cu" signal "GND7")
		(2 "B.Cu" signal "BOTTOM")
		(9 "F.Adhes" user "F.Adhesive")
		(11 "B.Adhes" user "B.Adhesive")
		(13 "F.Paste" user "Package Geometry/Pastemask Top")
		(15 "B.Paste" user "Package Geometry/Pastemask Bottom")
		(5 "F.SilkS" user "Ref Des/Silkscreen Top")
		(7 "B.SilkS" user "Ref Des/Silkscreen Bottom")
		(1 "F.Mask" user "Board Geometry/Soldermask Top")
		(3 "B.Mask" user "Board Geometry/Soldermask Bottom")
		(17 "Dwgs.User" user "User.Drawings")
		(19 "Cmts.User" user "User.Comments")
		(21 "Eco1.User" user "User.Eco1")
		(23 "Eco2.User" user "User.Eco2")
		(25 "Edge.Cuts" user "Board Geometry/Outline")
		(27 "Margin" user)
		(31 "F.CrtYd" user "Package Geometry/Place Bound Top")
		(29 "B.CrtYd" user "Package Geometry/Place Bound Bottom")
		(35 "F.Fab" user "Ref Des/Assembly Top")
		(33 "B.Fab" user "Ref Des/Assembly Bottom")
	)
	(footprint ""
		(layer "F.Cu")
		(at 20.014184 -112.314482)
		(property "Reference" "L16"
			(at 0 0 0)
			(layer "F.SilkS")
			(hide yes)
			(effects
				(font
					(size 1.27 1.27)
				)
			)
		)
		(property "Value" ""
			(at 0 0 0)
			(layer "F.Fab")
			(effects
				(font
					(size 1.27 1.27)
				)
			)
		)
		(duplicate_pad_numbers_are_jumpers no)
		(fp_line
			(start -1.27 -0.5842)
			(end 1.27 -0.5842)
			(stroke
				(width 0.1524)
				(type default)
			)
			(layer "F.SilkS")
		)
		(fp_line
			(start -1.27 -0.5588)
			(end -1.27 -0.5842)
			(stroke
				(width 0.1524)
				(type default)
			)
			(layer "F.SilkS")
		)
		(fp_line
			(start -1.27 0.5842)
			(end -1.27 -0.5842)
			(stroke
				(width 0.1524)
				(type default)
			)
			(layer "F.SilkS")
		)
		(fp_line
			(start -0.127 0.5842)
			(end -0.127 -0.5842)
			(stroke
				(width 0.1524)
				(type default)
			)
			(layer "F.SilkS")
		)
		(fp_line
			(start 0.127 0.5842)
			(end 0.127 -0.5842)
			(stroke
				(width 0.1524)
				(type default)
			)
			(layer "F.SilkS")
		)
		(fp_line
			(start 1.27 0.5842)
			(end -1.27 0.5842)
			(stroke
				(width 0.1524)
				(type default)
			)
			(layer "F.SilkS")
		)
		(fp_line
			(start 1.27 0.5842)
			(end 1.27 -0.5842)
			(stroke
				(width 0.1524)
				(type default)
			)
			(layer "F.SilkS")
		)
		(fp_line
			(start -1.194308 -0.406654)
			(end -0.9144 -0.406654)
			(stroke
				(width 0.1)
				(type default)
			)
			(layer "F.Fab")
		)
		(fp_line
			(start -1.194308 0.406654)
			(end -1.194308 -0.406654)
			(stroke
				(width 0.1)
				(type default)
			)
			(layer "F.Fab")
		)
		(fp_line
			(start -0.9144 -0.508)
			(end 0.9144 -0.508)
			(stroke
				(width 0.1)
				(type default)
			)
			(layer "F.Fab")
		)
		(fp_line
			(start -0.9144 -0.406654)
			(end -0.9144 -0.508)
			(stroke
				(width 0.1)
				(type default)
			)
			(layer "F.Fab")
		)
		(fp_line
			(start -0.9144 0.406654)
			(end -1.194308 0.406654)
			(stroke
				(width 0.1)
				(type default)
			)
			(layer "F.Fab")
		)
		(fp_line
			(start -0.9144 0.508)
			(end -0.9144 0.406654)
			(stroke
				(width 0.1)
				(type default)
			)
			(layer "F.Fab")
		)
		(fp_line
			(start 0.9144 -0.508)
			(end 0.9144 -0.406654)
			(stroke
				(width 0.1)
				(type default)
			)
			(layer "F.Fab")
		)
		(fp_line
			(start 0.9144 -0.406654)
			(end 1.1938 -0.406654)
			(stroke
				(width 0.1)
				(type default)
			)
			(layer "F.Fab")
		)
		(fp_line
			(start 0.9144 0.4064)
			(end 0.9144 0.508)
			(stroke
				(width 0.1)
				(type default)
			)
			(layer "F.Fab")
		)
		(fp_line
			(start 0.9144 0.508)
			(end -0.9144 0.508)
			(stroke
				(width 0.1)
				(type default)
			)
			(layer "F.Fab")
		)
		(fp_line
			(start 1.1938 -0.406654)
			(end 1.1938 0.4064)
			(stroke
				(width 0.1)
				(type default)
			)
			(layer "F.Fab")
		)
		(fp_line
			(start 1.1938 0.4064)
			(end 0.9144 0.4064)
			(stroke
				(width 0.1)
				(type default)
			)
			(layer "F.Fab")
		)
		(pad "1" smd rect
			(at -0.7366 0 270)
			(size 0.7112 0.8128)
			(layers "F.Cu" "F.Mask" "F.Paste")
			(net "P3V3_AUX")
		)
		(pad "2" smd rect
			(at 0.7366 0 270)
			(size 0.7112 0.8128)
			(layers "F.Cu" "F.Mask" "F.Paste")
			(net "P3V3_ADC128_VCC")
		)
	)
	(footprint ""
		(layer "F.Cu")
		(at 395.413738 -150.09241 -90)
		(property "Reference" "C569"
			(at 0 0 270)
			(layer "F.SilkS")
			(hide yes)
			(effects
				(font
					(size 1.27 1.27)
				)
			)
		)
		(property "Value" ""
			(at 0 0 270)
			(layer "F.Fab")
			(effects
				(font
					(size 1.27 1.27)
				)
			)
		)
		(duplicate_pad_numbers_are_jumpers no)
		(fp_line
			(start -0.7874 0.4064)
			(end -0.7874 -0.4064)
			(stroke
				(width 0.1524)
				(type default)
			)
			(layer "F.SilkS")
		)
		(fp_line
			(start 0.7874 0.4064)
			(end -0.7874 0.4064)
			(stroke
				(width 0.1524)
				(type default)
			)
			(layer "F.SilkS")
		)
		(fp_line
			(start -0.7874 -0.4064)
			(end 0.7874 -0.4064)
			(stroke
				(width 0.1524)
				(type default)
			)
			(layer "F.SilkS")
		)
		(fp_line
			(start 0.7874 -0.4064)
			(end 0.7874 0.4064)
			(stroke
				(width 0.1524)
				(type default)
			)
			(layer "F.SilkS")
		)
		(fp_line
			(start -0.67945 0.3048)
			(end -0.67945 -0.305054)
			(stroke
				(width 0.1)
				(type default)
			)
			(layer "F.Fab")
		)
		(fp_line
			(start -0.12065 0.3048)
			(end -0.67945 0.3048)
			(stroke
				(width 0.1)
				(type default)
			)
			(layer "F.Fab")
		)
		(fp_line
			(start 0.120396 0.3048)
			(end 0.120396 0.2794)
			(stroke
				(width 0.1)
				(type default)
			)
			(layer "F.Fab")
		)
		(fp_line
			(start 0.67945 0.3048)
			(end 0.120396 0.3048)
			(stroke
				(width 0.1)
				(type default)
			)
			(layer "F.Fab")
		)
		(fp_line
			(start -0.12065 0.2794)
			(end -0.12065 0.3048)
			(stroke
				(width 0.1)
				(type default)
			)
			(layer "F.Fab")
		)
		(fp_line
			(start 0.120396 0.2794)
			(end -0.12065 0.2794)
			(stroke
				(width 0.1)
				(type default)
			)
			(layer "F.Fab")
		)
		(fp_line
			(start -0.12065 -0.2794)
			(end 0.12065 -0.2794)
			(stroke
				(width 0.1)
				(type default)
			)
			(layer "F.Fab")
		)
		(fp_line
			(start 0.12065 -0.2794)
			(end 0.12065 -0.3048)
			(stroke
				(width 0.1)
				(type default)
			)
			(layer "F.Fab")
		)
		(fp_line
			(start 0.12065 -0.3048)
			(end 0.67945 -0.3048)
			(stroke
				(width 0.1)
				(type default)
			)
			(layer "F.Fab")
		)
		(fp_line
			(start 0.67945 -0.3048)
			(end 0.67945 0.3048)
			(stroke
				(width 0.1)
				(type default)
			)
			(layer "F.Fab")
		)
		(fp_line
			(start -0.67945 -0.305054)
			(end -0.12065 -0.305054)
			(stroke
				(width 0.1)
				(type default)
			)
			(layer "F.Fab")
		)
		(fp_line
			(start -0.12065 -0.305054)
			(end -0.12065 -0.2794)
			(stroke
				(width 0.1)
				(type default)
			)
			(layer "F.Fab")
		)
		(pad "1" smd circle
			(at -0.40005 0 270)
			(size 0 0)
			(layers "F.Cu" "F.Mask" "F.Paste")
			(net "P3V3_AUX")
		)
		(pad "2" smd circle
			(at 0.40005 0 270)
			(size 0 0)
			(layers "F.Cu" "F.Mask" "F.Paste")
			(net "GND")
		)
	)
	(footprint ""
		(layer "F.Cu")
		(at 416.3822 -17.612614 90)
		(property "Reference" "C857"
			(at 0 0 90)
			(layer "F.SilkS")
			(hide yes)
			(effects
				(font
					(size 1.27 1.27)
				)
			)
		)
		(property "Value" ""
			(at 0 0 90)
			(layer "F.Fab")
			(effects
				(font
					(size 1.27 1.27)
				)
			)
		)
		(duplicate_pad_numbers_are_jumpers no)
		(fp_line
			(start 0.299974 -0.150114)
			(end 0.299974 0.150114)
			(stroke
				(width 0.1)
				(type default)
			)
			(layer "F.Fab")
		)
		(fp_line
			(start -0.299974 -0.150114)
			(end 0.299974 -0.150114)
			(stroke
				(width 0.1)
				(type default)
			)
			(layer "F.Fab")
		)
		(fp_line
			(start 0.299974 0.150114)
			(end -0.299974 0.150114)
			(stroke
				(width 0.1)
				(type default)
			)
			(layer "F.Fab")
		)
		(fp_line
			(start -0.299974 0.150114)
			(end -0.299974 -0.150114)
			(stroke
				(width 0.1)
				(type default)
			)
			(layer "F.Fab")
		)
		(pad "1" smd rect
			(at -0.2667 0 90)
			(size 0.3048 0.381)
			(layers "F.Cu" "F.Mask" "F.Paste")
			(net "P5E_CPU0_PE1_TX_C_DP<6>")
		)
		(pad "2" smd rect
			(at 0.2667 0 90)
			(size 0.3048 0.381)
			(layers "F.Cu" "F.Mask" "F.Paste")
			(net "P5E_CPU0_PE1_TX_DP<6>")
		)
	)
)
